FILE_TYPE = CONNECTIVITY;
{Allegro Design Entry HDL 17.2-2016 S081 (4005846) 1/11/2022}
"PAGE_NUMBER" = 71;
0"NC";
1"PVDDCR_SOC_P1\g";
2"GND\g";
3"PVDDCR_SOC_P1\g";
4"GND\g";
5"PVDD11_S3_P1\g";
6"GND\g";
7"PVDD11_S3_P1\g";
8"GND\g";
9"PVDDCR_SOC_P1\g";
10"GND\g";
11"PVDD18_S5_P1\g";
12"GND\g";
13"GND\g";
14"PVDDIO_P1\g";
%"Q_CAP"
"1","(-8500,825)","0","pure_quanta","I1";
;
LOCATION"C2262"
$SEC"1"
CDS_SEC"1"
MATERIAL"X6S"
TOLERANCE"20%"
VALUE"22UF"
PART_NUMBER"CH622KMEB02"
VOLTAGE"4V"
PACK_TYPE"C0402"
CDS_LIB"pure_quanta";
"B"
$PN"2"8;
"A"
$PN"1"7;
%"UNIVERSAL_POWER"
"1","(-8525,5175)","0","pure_quanta_power","I10";
;
HDL_POWER"PVDDCR_SOC_P1"
CDS_LIB"pure_quanta_power";
"A"1;
%"Q_CAP"
"1","(-8050,825)","0","pure_quanta","I11";
;
LOCATION"C2267"
$SEC"1"
CDS_SEC"1"
MATERIAL"X6S"
TOLERANCE"20%"
VALUE"22UF"
PART_NUMBER"CH622KMEB02"
VOLTAGE"4V"
PACK_TYPE"C0402"
CDS_LIB"pure_quanta";
"B"
$PN"2"8;
"A"
$PN"1"7;
%"Q_CAP"
"1","(-7600,825)","0","pure_quanta","I12";
;
LOCATION"C3902"
$SEC"1"
CDS_SEC"1"
MATERIAL"X6S"
TOLERANCE"20%"
VALUE"22UF"
PART_NUMBER"CH622KMEB02"
VOLTAGE"4V"
PACK_TYPE"C0402"
CDS_LIB"pure_quanta";
"B"
$PN"2"8;
"A"
$PN"1"7;
%"Q_CAP"
"1","(-8050,1575)","0","pure_quanta","I13";
;
LOCATION"C2266"
$SEC"1"
CDS_SEC"1"
MATERIAL"X6S"
TOLERANCE"20%"
VALUE"22UF"
PART_NUMBER"CH622KMEB02"
VOLTAGE"4V"
PACK_TYPE"C0402"
CDS_LIB"pure_quanta";
"B"
$PN"2"6;
"A"
$PN"1"5;
%"Q_CAP"
"1","(-7600,1575)","0","pure_quanta","I14";
;
LOCATION"C2271"
$SEC"1"
CDS_SEC"1"
MATERIAL"X6S"
TOLERANCE"20%"
VALUE"22UF"
PART_NUMBER"CH622KMEB02"
VOLTAGE"4V"
PACK_TYPE"C0402"
CDS_LIB"pure_quanta";
"B"
$PN"2"6;
"A"
$PN"1"5;
%"Q_CAP"
"1","(-7150,825)","0","pure_quanta","I15";
;
LOCATION"C3903"
$SEC"1"
CDS_SEC"1"
MATERIAL"X6S"
TOLERANCE"20%"
VALUE"22UF"
PART_NUMBER"CH622KMEB02"
VOLTAGE"4V"
PACK_TYPE"C0402"
CDS_LIB"pure_quanta";
"B"
$PN"2"8;
"A"
$PN"1"7;
%"Q_CAP"
"1","(-6700,825)","0","pure_quanta","I16";
;
LOCATION"C3904"
$SEC"1"
CDS_SEC"1"
MATERIAL"X6S"
TOLERANCE"20%"
VALUE"22UF"
PART_NUMBER"CH622KMEB02"
VOLTAGE"4V"
PACK_TYPE"C0402"
CDS_LIB"pure_quanta";
"B"
$PN"2"8;
"A"
$PN"1"7;
%"UNIVERSAL_GND"
"1","(-6250,450)","0","pure_quanta_power","I17";
;
CDS_LIB"pure_quanta_power"
HDL_POWER"GND";
"A"8;
%"Q_CAP"
"1","(-6250,825)","0","pure_quanta","I18";
;
LOCATION"C3905"
$SEC"1"
CDS_SEC"1"
MATERIAL"X6S"
TOLERANCE"20%"
VALUE"22UF"
PART_NUMBER"CH622KMEB02"
VOLTAGE"4V"
PACK_TYPE"C0402"
CDS_LIB"pure_quanta";
"B"
$PN"2"8;
"A"
$PN"1"7;
%"Q_CAP"
"1","(-7150,1575)","0","pure_quanta","I19";
;
LOCATION"C2275"
$SEC"1"
CDS_SEC"1"
MATERIAL"X6S"
TOLERANCE"20%"
VALUE"22UF"
PART_NUMBER"CH622KMEB02"
VOLTAGE"4V"
PACK_TYPE"C0402"
CDS_LIB"pure_quanta";
"B"
$PN"2"6;
"A"
$PN"1"5;
%"UNIVERSAL_POWER"
"1","(-8500,1100)","0","pure_quanta_power","I2";
;
HDL_POWER"PVDD11_S3_P1"
CDS_LIB"pure_quanta_power";
"A"7;
%"Q_CAP"
"1","(-6700,1575)","0","pure_quanta","I20";
;
LOCATION"C2279"
$SEC"1"
CDS_SEC"1"
MATERIAL"X6S"
TOLERANCE"20%"
VALUE"22UF"
PART_NUMBER"CH622KMEB02"
VOLTAGE"4V"
PACK_TYPE"C0402"
CDS_LIB"pure_quanta";
"B"
$PN"2"6;
"A"
$PN"1"5;
%"Q_CAP"
"1","(-6250,1575)","0","pure_quanta","I21";
;
LOCATION"C2282"
$SEC"1"
CDS_SEC"1"
MATERIAL"X6S"
TOLERANCE"20%"
VALUE"22UF"
PART_NUMBER"CH622KMEB02"
VOLTAGE"4V"
PACK_TYPE"C0402"
CDS_LIB"pure_quanta";
"B"
$PN"2"6;
"A"
$PN"1"5;
%"UNIVERSAL_GND"
"1","(-8075,3025)","0","pure_quanta_power","I22";
;
CDS_LIB"pure_quanta_power"
HDL_POWER"GND";
"A"10;
%"Q_CAP"
"1","(-8075,3375)","0","pure_quanta","I23";
;
LOCATION"C3901"
$SEC"1"
CDS_SEC"1"
MATERIAL"X6S"
TOLERANCE"20%"
VALUE"22UF"
PART_NUMBER"CH622KMEB02"
VOLTAGE"4V"
PACK_TYPE"C0402"
CDS_LIB"pure_quanta";
"B"
$PN"2"10;
"A"
$PN"1"9;
%"Q_CAP"
"1","(-5800,1575)","0","pure_quanta","I24";
;
LOCATION"C2285"
$SEC"1"
CDS_SEC"1"
MATERIAL"X6S"
TOLERANCE"20%"
VALUE"22UF"
PART_NUMBER"CH622KMEB02"
VOLTAGE"4V"
PACK_TYPE"C0402"
CDS_LIB"pure_quanta";
"B"
$PN"2"6;
"A"
$PN"1"5;
%"Q_CAP"
"1","(-5350,1575)","0","pure_quanta","I25";
;
LOCATION"C2287"
$SEC"1"
CDS_SEC"1"
MATERIAL"X6S"
TOLERANCE"20%"
VALUE"22UF"
PART_NUMBER"CH622KMEB02"
VOLTAGE"4V"
PACK_TYPE"C0402"
CDS_LIB"pure_quanta";
"B"
$PN"2"6;
"A"
$PN"1"5;
%"Q_CAP"
"1","(-4900,1575)","0","pure_quanta","I26";
;
LOCATION"C2289"
$SEC"1"
CDS_SEC"1"
MATERIAL"X6S"
TOLERANCE"20%"
VALUE"22UF"
PART_NUMBER"CH622KMEB02"
VOLTAGE"4V"
PACK_TYPE"C0402"
CDS_LIB"pure_quanta";
"B"
$PN"2"6;
"A"
$PN"1"5;
%"UNIVERSAL_GND"
"1","(-4500,1200)","0","pure_quanta_power","I27";
;
CDS_LIB"pure_quanta_power"
HDL_POWER"GND";
"A"6;
%"Q_CAP"
"1","(-4500,1575)","0","pure_quanta","I28";
;
LOCATION"C2291"
$SEC"1"
CDS_SEC"1"
MATERIAL"X6S"
TOLERANCE"20%"
VALUE"22UF"
PART_NUMBER"CH622KMEB02"
VOLTAGE"4V"
PACK_TYPE"C0402"
CDS_LIB"pure_quanta";
"B"
$PN"2"6;
"A"
$PN"1"5;
%"UNIVERSAL_GND"
"1","(-4525,3725)","0","pure_quanta_power","I29";
;
CDS_LIB"pure_quanta_power"
HDL_POWER"GND";
"A"4;
%"Q_CAP"
"1","(-8500,1575)","0","pure_quanta","I3";
;
LOCATION"C2261"
$SEC"1"
CDS_SEC"1"
MATERIAL"X6S"
TOLERANCE"20%"
VALUE"22UF"
PART_NUMBER"CH622KMEB02"
VOLTAGE"4V"
PACK_TYPE"C0402"
CDS_LIB"pure_quanta";
"B"
$PN"2"6;
"A"
$PN"1"5;
%"Q_CAP"
"1","(-8075,4100)","0","pure_quanta","I30";
;
LOCATION"C2264"
$SEC"1"
CDS_SEC"1"
MATERIAL"X6S"
TOLERANCE"20%"
VALUE"22UF"
PART_NUMBER"CH622KMEB02"
VOLTAGE"4V"
PACK_TYPE"C0402"
CDS_LIB"pure_quanta";
"B"
$PN"2"4;
"A"
$PN"1"3;
%"Q_CAP"
"1","(-8075,4900)","0","pure_quanta","I31";
;
LOCATION"C2263"
$SEC"1"
CDS_SEC"1"
MATERIAL"X6S"
TOLERANCE"20%"
VALUE"22UF"
PART_NUMBER"CH622KMEB02"
VOLTAGE"4V"
PACK_TYPE"C0402"
CDS_LIB"pure_quanta";
"B"
$PN"2"2;
"A"
$PN"1"1;
%"Q_CAP"
"1","(-7625,4100)","0","pure_quanta","I32";
;
LOCATION"C2269"
$SEC"1"
CDS_SEC"1"
MATERIAL"X6S"
TOLERANCE"20%"
VALUE"22UF"
PART_NUMBER"CH622KMEB02"
VOLTAGE"4V"
PACK_TYPE"C0402"
CDS_LIB"pure_quanta";
"B"
$PN"2"4;
"A"
$PN"1"3;
%"Q_CAP"
"1","(-7625,4900)","0","pure_quanta","I33";
;
LOCATION"C2268"
$SEC"1"
CDS_SEC"1"
MATERIAL"X6S"
TOLERANCE"20%"
VALUE"22UF"
PART_NUMBER"CH622KMEB02"
VOLTAGE"4V"
PACK_TYPE"C0402"
CDS_LIB"pure_quanta";
"B"
$PN"2"2;
"A"
$PN"1"1;
%"Q_CAP"
"1","(-7175,4900)","0","pure_quanta","I34";
;
LOCATION"C2272"
$SEC"1"
CDS_SEC"1"
MATERIAL"X6S"
TOLERANCE"20%"
VALUE"22UF"
PART_NUMBER"CH622KMEB02"
VOLTAGE"4V"
PACK_TYPE"C0402"
CDS_LIB"pure_quanta";
"B"
$PN"2"2;
"A"
$PN"1"1;
%"Q_CAP"
"1","(-7175,4100)","0","pure_quanta","I35";
;
LOCATION"C2273"
$SEC"1"
CDS_SEC"1"
MATERIAL"X6S"
TOLERANCE"20%"
VALUE"22UF"
PART_NUMBER"CH622KMEB02"
VOLTAGE"4V"
PACK_TYPE"C0402"
CDS_LIB"pure_quanta";
"B"
$PN"2"4;
"A"
$PN"1"3;
%"Q_CAP"
"1","(-6725,4100)","0","pure_quanta","I36";
;
LOCATION"C2277"
$SEC"1"
CDS_SEC"1"
MATERIAL"X6S"
TOLERANCE"20%"
VALUE"22UF"
PART_NUMBER"CH622KMEB02"
VOLTAGE"4V"
PACK_TYPE"C0402"
CDS_LIB"pure_quanta";
"B"
$PN"2"4;
"A"
$PN"1"3;
%"Q_CAP"
"1","(-6275,4100)","0","pure_quanta","I37";
;
LOCATION"C2281"
$SEC"1"
CDS_SEC"1"
MATERIAL"X6S"
TOLERANCE"20%"
VALUE"22UF"
PART_NUMBER"CH622KMEB02"
VOLTAGE"4V"
PACK_TYPE"C0402"
CDS_LIB"pure_quanta";
"B"
$PN"2"4;
"A"
$PN"1"3;
%"Q_CAP"
"1","(-6275,4900)","0","pure_quanta","I38";
;
LOCATION"C2280"
$SEC"1"
CDS_SEC"1"
MATERIAL"X6S"
TOLERANCE"20%"
VALUE"22UF"
PART_NUMBER"CH622KMEB02"
VOLTAGE"4V"
PACK_TYPE"C0402"
CDS_LIB"pure_quanta";
"B"
$PN"2"2;
"A"
$PN"1"1;
%"Q_CAP"
"1","(-5825,4100)","0","pure_quanta","I39";
;
LOCATION"C2284"
$SEC"1"
CDS_SEC"1"
MATERIAL"X6S"
TOLERANCE"20%"
VALUE"22UF"
PART_NUMBER"CH622KMEB02"
VOLTAGE"4V"
PACK_TYPE"C0402"
CDS_LIB"pure_quanta";
"B"
$PN"2"4;
"A"
$PN"1"3;
%"UNIVERSAL_POWER"
"1","(-8500,1850)","0","pure_quanta_power","I4";
;
HDL_POWER"PVDD11_S3_P1"
CDS_LIB"pure_quanta_power";
"A"5;
%"Q_CAP"
"1","(-5825,4900)","0","pure_quanta","I40";
;
LOCATION"C2283"
$SEC"1"
CDS_SEC"1"
MATERIAL"X6S"
TOLERANCE"20%"
VALUE"22UF"
PART_NUMBER"CH622KMEB02"
VOLTAGE"4V"
PACK_TYPE"C0402"
CDS_LIB"pure_quanta";
"B"
$PN"2"2;
"A"
$PN"1"1;
%"Q_CAP"
"1","(-5375,4100)","0","pure_quanta","I41";
;
LOCATION"C3906"
$SEC"1"
CDS_SEC"1"
MATERIAL"X6S"
TOLERANCE"20%"
VALUE"22UF"
PART_NUMBER"CH622KMEB02"
VOLTAGE"4V"
PACK_TYPE"C0402"
CDS_LIB"pure_quanta";
"B"
$PN"2"4;
"A"
$PN"1"3;
%"Q_CAP"
"1","(-5375,4900)","0","pure_quanta","I42";
;
LOCATION"C2286"
$SEC"1"
CDS_SEC"1"
MATERIAL"X6S"
TOLERANCE"20%"
VALUE"22UF"
PART_NUMBER"CH622KMEB02"
VOLTAGE"4V"
PACK_TYPE"C0402"
CDS_LIB"pure_quanta";
"B"
$PN"2"2;
"A"
$PN"1"1;
%"Q_CAP"
"1","(-4925,4100)","0","pure_quanta","I43";
;
LOCATION"C3907"
$SEC"1"
CDS_SEC"1"
MATERIAL"X6S"
TOLERANCE"20%"
VALUE"22UF"
PART_NUMBER"CH622KMEB02"
VOLTAGE"4V"
PACK_TYPE"C0402"
CDS_LIB"pure_quanta";
"B"
$PN"2"4;
"A"
$PN"1"3;
%"Q_CAP"
"1","(-4925,4900)","0","pure_quanta","I44";
;
LOCATION"C2288"
$SEC"1"
CDS_SEC"1"
MATERIAL"X6S"
TOLERANCE"20%"
VALUE"22UF"
PART_NUMBER"CH622KMEB02"
VOLTAGE"4V"
PACK_TYPE"C0402"
CDS_LIB"pure_quanta";
"B"
$PN"2"2;
"A"
$PN"1"1;
%"Q_CAP"
"1","(-4525,4100)","0","pure_quanta","I45";
;
LOCATION"C3908"
$SEC"1"
CDS_SEC"1"
MATERIAL"X6S"
TOLERANCE"20%"
VALUE"22UF"
PART_NUMBER"CH622KMEB02"
VOLTAGE"4V"
PACK_TYPE"C0402"
CDS_LIB"pure_quanta";
"B"
$PN"2"4;
"A"
$PN"1"3;
%"UNIVERSAL_GND"
"1","(-4525,4525)","0","pure_quanta_power","I46";
;
CDS_LIB"pure_quanta_power"
HDL_POWER"GND";
"A"2;
%"Q_CAP"
"1","(-4525,4900)","0","pure_quanta","I47";
;
LOCATION"C2290"
$SEC"1"
CDS_SEC"1"
MATERIAL"X6S"
TOLERANCE"20%"
VALUE"22UF"
PART_NUMBER"CH622KMEB02"
VOLTAGE"4V"
PACK_TYPE"C0402"
CDS_LIB"pure_quanta";
"B"
$PN"2"2;
"A"
$PN"1"1;
%"UNIVERSAL_POWER"
"1","(-3600,3650)","0","pure_quanta_power","I48";
;
HDL_POWER"PVDD18_S5_P1"
CDS_LIB"pure_quanta_power";
"A"11;
%"Q_CAP"
"1","(-3600,3375)","0","pure_quanta","I49";
;
LOCATION"C2292"
$SEC"1"
CDS_SEC"1"
MATERIAL"X6S"
TOLERANCE"20%"
VALUE"22UF"
PART_NUMBER"CH622KMEB02"
VOLTAGE"4V"
PACK_TYPE"C0402"
CDS_LIB"pure_quanta";
"B"
$PN"2"12;
"A"
$PN"1"11;
%"Q_CAP"
"1","(-8525,3375)","0","pure_quanta","I5";
;
LOCATION"C3900"
$SEC"1"
CDS_SEC"1"
MATERIAL"X6S"
TOLERANCE"20%"
VALUE"22UF"
PART_NUMBER"CH622KMEB02"
VOLTAGE"4V"
PACK_TYPE"C0402"
CDS_LIB"pure_quanta";
"B"
$PN"2"10;
"A"
$PN"1"9;
%"Q_CAP"
"1","(-3150,3375)","0","pure_quanta","I50";
;
LOCATION"C2293"
$SEC"1"
CDS_SEC"1"
MATERIAL"X6S"
TOLERANCE"20%"
VALUE"22UF"
PART_NUMBER"CH622KMEB02"
VOLTAGE"4V"
PACK_TYPE"C0402"
CDS_LIB"pure_quanta";
"B"
$PN"2"12;
"A"
$PN"1"11;
%"UNIVERSAL_GND"
"1","(-2700,3025)","0","pure_quanta_power","I51";
;
CDS_LIB"pure_quanta_power"
HDL_POWER"GND";
"A"12;
%"Q_CAP"
"1","(-2700,3375)","0","pure_quanta","I52";
;
LOCATION"C3909"
$SEC"1"
CDS_SEC"1"
MATERIAL"X6S"
TOLERANCE"20%"
VALUE"22UF"
PART_NUMBER"CH622KMEB02"
VOLTAGE"4V"
PACK_TYPE"C0402"
CDS_LIB"pure_quanta";
"B"
$PN"2"12;
"A"
$PN"1"11;
%"Q_CAP"
"1","(-3600,4975)","0","pure_quanta","I53";
;
LOCATION"C2260"
$SEC"1"
CDS_SEC"1"
MATERIAL"X6S"
TOLERANCE"20%"
VALUE"22UF"
PART_NUMBER"CH622KMEB02"
VOLTAGE"4V"
PACK_TYPE"C0402"
CDS_LIB"pure_quanta";
"B"
$PN"2"13;
"A"
$PN"1"14;
%"Q_CAP"
"1","(-3150,4975)","0","pure_quanta","I54";
;
LOCATION"C2265"
$SEC"1"
CDS_SEC"1"
MATERIAL"X6S"
TOLERANCE"20%"
VALUE"22UF"
PART_NUMBER"CH622KMEB02"
VOLTAGE"4V"
PACK_TYPE"C0402"
CDS_LIB"pure_quanta";
"B"
$PN"2"13;
"A"
$PN"1"14;
%"UNIVERSAL_POWER"
"1","(-3600,5250)","0","pure_quanta_power","I55";
;
HDL_POWER"PVDDIO_P1"
CDS_LIB"pure_quanta_power";
"A"14;
%"Q_CAP"
"1","(-2700,4975)","0","pure_quanta","I56";
;
LOCATION"C2270"
$SEC"1"
CDS_SEC"1"
MATERIAL"X6S"
TOLERANCE"20%"
VALUE"22UF"
PART_NUMBER"CH622KMEB02"
VOLTAGE"4V"
PACK_TYPE"C0402"
CDS_LIB"pure_quanta";
"B"
$PN"2"13;
"A"
$PN"1"14;
%"Q_CAP"
"1","(-2250,4975)","0","pure_quanta","I57";
;
LOCATION"C2274"
$SEC"1"
CDS_SEC"1"
MATERIAL"X6S"
TOLERANCE"20%"
VALUE"22UF"
PART_NUMBER"CH622KMEB02"
VOLTAGE"4V"
PACK_TYPE"C0402"
CDS_LIB"pure_quanta";
"B"
$PN"2"13;
"A"
$PN"1"14;
%"Q_CAP"
"1","(-1800,4975)","0","pure_quanta","I58";
;
LOCATION"C2278"
$SEC"1"
CDS_SEC"1"
MATERIAL"X6S"
TOLERANCE"20%"
VALUE"22UF"
PART_NUMBER"CH622KMEB02"
VOLTAGE"4V"
PACK_TYPE"C0402"
CDS_LIB"pure_quanta";
"B"
$PN"2"13;
"A"
$PN"1"14;
%"Q_CAP"
"1","(-1350,4975)","0","pure_quanta","I59";
;
LOCATION"C3910"
$SEC"1"
CDS_SEC"1"
MATERIAL"X6S"
TOLERANCE"20%"
VALUE"22UF"
PART_NUMBER"CH622KMEB02"
VOLTAGE"4V"
PACK_TYPE"C0402"
CDS_LIB"pure_quanta";
"B"
$PN"2"13;
"A"
$PN"1"14;
%"UNIVERSAL_POWER"
"1","(-8525,3650)","0","pure_quanta_power","I6";
;
HDL_POWER"PVDDCR_SOC_P1"
CDS_LIB"pure_quanta_power";
"A"9;
%"UNIVERSAL_GND"
"1","(-900,4625)","0","pure_quanta_power","I60";
;
CDS_LIB"pure_quanta_power"
HDL_POWER"GND";
"A"13;
%"Q_CAP"
"1","(-900,4975)","0","pure_quanta","I61";
;
LOCATION"C3911"
$SEC"1"
CDS_SEC"1"
MATERIAL"X6S"
TOLERANCE"20%"
VALUE"22UF"
PART_NUMBER"CH622KMEB02"
VOLTAGE"4V"
PACK_TYPE"C0402"
CDS_LIB"pure_quanta";
"B"
$PN"2"13;
"A"
$PN"1"14;
%"Q_CAP"
"1","(-6725,4900)","0","pure_quanta","I62";
;
LOCATION"C2276"
$SEC"1"
CDS_SEC"1"
MATERIAL"X6S"
TOLERANCE"20%"
VALUE"22UF"
PART_NUMBER"CH622KMEB02"
VOLTAGE"4V"
PACK_TYPE"C0402"
CDS_LIB"pure_quanta";
"B"
$PN"2"2;
"A"
$PN"1"1;
%"Q_CAP"
"1","(-8525,4100)","0","pure_quanta","I7";
;
LOCATION"C2259"
$SEC"1"
CDS_SEC"1"
MATERIAL"X6S"
TOLERANCE"20%"
VALUE"22UF"
PART_NUMBER"CH622KMEB02"
VOLTAGE"4V"
PACK_TYPE"C0402"
CDS_LIB"pure_quanta";
"B"
$PN"2"4;
"A"
$PN"1"3;
%"UNIVERSAL_POWER"
"1","(-8525,4375)","0","pure_quanta_power","I8";
;
HDL_POWER"PVDDCR_SOC_P1"
CDS_LIB"pure_quanta_power";
"A"3;
%"Q_CAP"
"1","(-8525,4900)","0","pure_quanta","I9";
;
LOCATION"C2258"
$SEC"1"
CDS_SEC"1"
MATERIAL"X6S"
TOLERANCE"20%"
VALUE"22UF"
PART_NUMBER"CH622KMEB02"
VOLTAGE"4V"
PACK_TYPE"C0402"
CDS_LIB"pure_quanta";
"B"
$PN"2"2;
"A"
$PN"1"1;
END.
